# S9S_MB_2U (Grand Teton) — schematic netlist excerpt (pin names and nets, part order shuffled) for the footprints in the layout excerpt that follows; sources: Cadence DE-HDL packaged netlist, KiCad conversion of 03242023_DA0F0TMBIJ0_F0T_Motherboard_J_brd_V01_OCP.brd

C932  Q_CAP_DIFFBUS  DIFF BUS_0.22UF 6.3V 20% X6S  pkg C0201  page 173 : \1\ = P5E_CPU0_PE0_TX_C_DN<0> ; \2\ = P5E_CPU0_PE0_TX_DN<0>
C1573  Q_CAP_DIFFBUS  DIFF BUS_0.22UF 6.3V 20% X6S  pkg C0201  page 175 : \1\ = P5E_CPU0_PE4_TX_C_DP<3> ; \2\ = P5E_CPU0_PE4_TX_DP<3>

U85  NC7SB3157  NC7SB3157P6X IC  pkg SMLF  page 134
  B1  = JTAG_BMC_PCH_TCK
  GND  = GND
  B0  = JTAG_BMC_CPU_TCK
  A  = JTAG_BMC_DBP_TCK
  VCC  = P3V3_AUX
  S  = FM_JTAG_TCK_MUX_SEL

(kicad_pcb
	(version 20260206)
	(generator "pcbnew")
	(generator_version "10.0")
	(general
		(thickness 1.6)
		(legacy_teardrops no)
	)
	(paper "A4")
	(title_block
		(title "03242023_DA0F0TMBIJ0_F0T_Motherboard_J_brd_V01_OCP.brd")
		(comment 1 "Grand Teton / footprints 14-16 of 6105")
	)
	(layers
		(0 "F.Cu" signal "TOP")
		(4 "In1.Cu" signal "GND")
		(6 "In2.Cu" signal "IN1")
		(8 "In3.Cu" signal "GND1")
		(10 "In4.Cu" signal "IN2")
		(12 "In5.Cu" signal "GND2")
		(14 "In6.Cu" signal "IN3")
		(16 "In7.Cu" signal "GND3")
		(18 "In8.Cu" signal "VCC")
		(20 "In9.Cu" signal "VCC1")
		(22 "In10.Cu" signal "GND4")
		(24 "In11.Cu" signal "IN4")
		(26 "In12.Cu" signal "GND5")
		(28 "In13.Cu" signal "IN5")
		(30 "In14.Cu" signal "GND6")
		(32 "In15.Cu" signal "IN6")
		(34 "In16.Cu" signal "GND7")
		(2 "B.Cu" signal "BOTTOM")
		(9 "F.Adhes" user "F.Adhesive")
		(11 "B.Adhes" user "B.Adhesive")
		(13 "F.Paste" user "Package Geometry/Pastemask Top")
		(15 "B.Paste" user "Package Geometry/Pastemask Bottom")
		(5 "F.SilkS" user "Ref Des/Silkscreen Top")
		(7 "B.SilkS" user "Ref Des/Silkscreen Bottom")
		(1 "F.Mask" user "Board Geometry/Soldermask Top")
		(3 "B.Mask" user "Board Geometry/Soldermask Bottom")
		(17 "Dwgs.User" user "User.Drawings")
		(19 "Cmts.User" user "User.Comments")
		(21 "Eco1.User" user "User.Eco1")
		(23 "Eco2.User" user "User.Eco2")
		(25 "Edge.Cuts" user "Board Geometry/Outline")
		(27 "Margin" user)
		(31 "F.CrtYd" user "Package Geometry/Place Bound Top")
		(29 "B.CrtYd" user "Package Geometry/Place Bound Bottom")
		(35 "F.Fab" user "Ref Des/Assembly Top")
		(33 "B.Fab" user "Ref Des/Assembly Bottom")
	)
	(footprint ""
		(layer "F.Cu")
		(at 351.249488 -408.517344 -90)
		(property "Reference" "C932"
			(at 0 0 270)
			(layer "F.SilkS")
			(hide yes)
			(effects
				(font
					(size 1.27 1.27)
				)
			)
		)
		(property "Value" ""
			(at 0 0 270)
			(layer "F.Fab")
			(effects
				(font
					(size 1.27 1.27)
				)
			)
		)
		(duplicate_pad_numbers_are_jumpers no)
		(fp_line
			(start -0.299974 0.150114)
			(end -0.299974 -0.150114)
			(stroke
				(width 0.1)
				(type default)
			)
			(layer "F.Fab")
		)
		(fp_line
			(start 0.299974 0.150114)
			(end -0.299974 0.150114)
			(stroke
				(width 0.1)
				(type default)
			)
			(layer "F.Fab")
		)
		(fp_line
			(start -0.299974 -0.150114)
			(end 0.299974 -0.150114)
			(stroke
				(width 0.1)
				(type default)
			)
			(layer "F.Fab")
		)
		(fp_line
			(start 0.299974 -0.150114)
			(end 0.299974 0.150114)
			(stroke
				(width 0.1)
				(type default)
			)
			(layer "F.Fab")
		)
		(pad "1" smd rect
			(at -0.2667 0 270)
			(size 0.3048 0.381)
			(layers "F.Cu" "F.Mask" "F.Paste")
			(net "P5E_CPU0_PE0_TX_C_DN<0>")
		)
		(pad "2" smd rect
			(at 0.2667 0 270)
			(size 0.3048 0.381)
			(layers "F.Cu" "F.Mask" "F.Paste")
			(net "P5E_CPU0_PE0_TX_DN<0>")
		)
	)
	(footprint ""
		(layer "F.Cu")
		(at 104.93121 -60.128404)
		(property "Reference" "U85"
			(at -3.9243 0.42545 0)
			(unlocked yes)
			(layer "F.SilkS")
			(effects
				(font
					(size 0.7874 0.5842)
					(thickness 0.1524)
				)
			)
		)
		(property "Value" ""
			(at 0 0 0)
			(layer "F.Fab")
			(effects
				(font
					(size 1.27 1.27)
				)
			)
		)
		(duplicate_pad_numbers_are_jumpers no)
		(fp_line
			(start -1.7272 1.1176)
			(end -1.7272 -1.1176)
			(stroke
				(width 0.1524)
				(type default)
			)
			(layer "F.SilkS")
		)
		(fp_line
			(start -0.254 -1.1176)
			(end -1.7272 -1.1176)
			(stroke
				(width 0.1524)
				(type default)
			)
			(layer "F.SilkS")
		)
		(fp_line
			(start 0 -0.7366)
			(end -0.254 -1.1176)
			(stroke
				(width 0.1524)
				(type default)
			)
			(layer "F.SilkS")
		)
		(fp_line
			(start 0.254 -1.1176)
			(end 0 -0.7366)
			(stroke
				(width 0.1524)
				(type default)
			)
			(layer "F.SilkS")
		)
		(fp_line
			(start 1.7272 -1.1176)
			(end 0.254 -1.1176)
			(stroke
				(width 0.1524)
				(type default)
			)
			(layer "F.SilkS")
		)
		(fp_line
			(start 1.7272 -1.1176)
			(end 1.7272 1.1176)
			(stroke
				(width 0.1524)
				(type default)
			)
			(layer "F.SilkS")
		)
		(fp_line
			(start 1.7272 1.1176)
			(end -1.7272 1.1176)
			(stroke
				(width 0.1524)
				(type default)
			)
			(layer "F.SilkS")
		)
		(fp_poly
			(pts
				(xy -2.7178 -0.268986) (xy -2.7178 -1.030986) (xy -1.9558 -0.649986)
			)
			(stroke
				(width 0)
				(type default)
			)
			(fill yes)
			(layer "F.SilkS")
		)
		(fp_line
			(start -1.5748 -1.1176)
			(end -1.5748 1.1176)
			(stroke
				(width 0.1)
				(type default)
			)
			(layer "F.Fab")
		)
		(fp_line
			(start -1.5748 1.1176)
			(end 1.5748 1.1176)
			(stroke
				(width 0.1)
				(type default)
			)
			(layer "F.Fab")
		)
		(fp_line
			(start 1.5748 -1.1176)
			(end -1.5748 -1.1176)
			(stroke
				(width 0.1)
				(type default)
			)
			(layer "F.Fab")
		)
		(fp_line
			(start 1.5748 1.1176)
			(end 1.5748 -1.1176)
			(stroke
				(width 0.1)
				(type default)
			)
			(layer "F.Fab")
		)
		(fp_poly
			(pts
				(xy -1.9558 -0.649986) (xy -2.7178 -0.268986) (xy -2.7178 -1.030986)
			)
			(stroke
				(width 0)
				(type default)
			)
			(fill yes)
			(layer "F.Fab")
		)
		(pad "1" smd rect
			(at -0.999998 -0.649986 270)
			(size 0.3556 1.1176)
			(layers "F.Cu" "F.Mask" "F.Paste")
			(net "JTAG_BMC_PCH_TCK")
		)
		(pad "2" smd rect
			(at -0.999998 0 270)
			(size 0.3556 1.1176)
			(layers "F.Cu" "F.Mask" "F.Paste")
			(net "GND")
		)
		(pad "3" smd rect
			(at -0.999998 0.649986 270)
			(size 0.3556 1.1176)
			(layers "F.Cu" "F.Mask" "F.Paste")
			(net "JTAG_BMC_CPU_TCK")
		)
		(pad "4" smd rect
			(at 0.999998 0.649986 270)
			(size 0.3556 1.1176)
			(layers "F.Cu" "F.Mask" "F.Paste")
			(net "JTAG_BMC_DBP_TCK")
		)
		(pad "5" smd rect
			(at 0.999998 0 270)
			(size 0.3556 1.1176)
			(layers "F.Cu" "F.Mask" "F.Paste")
			(net "P3V3_AUX")
		)
		(pad "6" smd rect
			(at 0.999998 -0.649986 270)
			(size 0.3556 1.1176)
			(layers "F.Cu" "F.Mask" "F.Paste")
			(net "FM_JTAG_TCK_MUX_SEL")
		)
	)
	(footprint ""
		(layer "F.Cu")
		(at 314.058808 -402.371052 -90)
		(property "Reference" "C1573"
			(at 0 0 270)
			(layer "F.SilkS")
			(hide yes)
			(effects
				(font
					(size 1.27 1.27)
				)
			)
		)
		(property "Value" ""
			(at 0 0 270)
			(layer "F.Fab")
			(effects
				(font
					(size 1.27 1.27)
				)
			)
		)
		(duplicate_pad_numbers_are_jumpers no)
		(fp_line
			(start -0.299974 0.150114)
			(end -0.299974 -0.150114)
			(stroke
				(width 0.1)
				(type default)
			)
			(layer "F.Fab")
		)
		(fp_line
			(start 0.299974 0.150114)
			(end -0.299974 0.150114)
			(stroke
				(width 0.1)
				(type default)
			)
			(layer "F.Fab")
		)
		(fp_line
			(start -0.299974 -0.150114)
			(end 0.299974 -0.150114)
			(stroke
				(width 0.1)
				(type default)
			)
			(layer "F.Fab")
		)
		(fp_line
			(start 0.299974 -0.150114)
			(end 0.299974 0.150114)
			(stroke
				(width 0.1)
				(type default)
			)
			(layer "F.Fab")
		)
		(pad "1" smd rect
			(at -0.2667 0 270)
			(size 0.3048 0.381)
			(layers "F.Cu" "F.Mask" "F.Paste")
			(net "P5E_CPU0_PE4_TX_C_DP<3>")
		)
		(pad "2" smd rect
			(at 0.2667 0 270)
			(size 0.3048 0.381)
			(layers "F.Cu" "F.Mask" "F.Paste")
			(net "P5E_CPU0_PE4_TX_DP<3>")
		)
	)
)
